(kicad_pcb
	(version 20241229)
	(generator "pcbnew")
	(generator_version "9.0")
	(general
		(thickness 1.6296)
		(legacy_teardrops no)
	)
	(paper "A3")
	(title_block
		(title "Thunderbolt to 10GbE adapter")
		(date "2026-04-21")
		(rev "1.1.0")
		(company "Antmicro Ltd")
		(comment 1 "www.antmicro.com")
		(comment 9 "footprint 4 of 703 (U4), pads 1-79 of 337")
	)
	(layers
		(0 "F.Cu" signal)
		(4 "In1.Cu" signal)
		(6 "In2.Cu" signal)
		(8 "In3.Cu" signal)
		(10 "In4.Cu" signal)
		(12 "In5.Cu" signal)
		(14 "In6.Cu" signal)
		(2 "B.Cu" signal)
		(9 "F.Adhes" user "F.Adhesive")
		(11 "B.Adhes" user "B.Adhesive")
		(13 "F.Paste" user)
		(15 "B.Paste" user)
		(5 "F.SilkS" user "F.Silkscreen")
		(7 "B.SilkS" user "B.Silkscreen")
		(1 "F.Mask" user)
		(3 "B.Mask" user)
		(17 "Dwgs.User" user "User.Drawings")
		(19 "Cmts.User" user "User.Comments")
		(21 "Eco1.User" user "User.Eco1")
		(23 "Eco2.User" user "User.Eco2")
		(25 "Edge.Cuts" user)
		(27 "Margin" user)
		(31 "F.CrtYd" user "F.Courtyard")
		(29 "B.CrtYd" user "B.Courtyard")
		(35 "F.Fab" user)
		(33 "B.Fab" user)
	)
	(footprint "antmicro-footprints:JHL6340SLLSQ"
		(layer "F.Cu")
		(at 128.5 123.95 180)
		(property "Reference" "U4"
			(at 4.9 6.15 0)
			(unlocked yes)
			(layer "F.SilkS")
			(effects
				(font
					(size 0.7 0.7)
					(thickness 0.15)
				)
			)
		)
		(property "Value" "JHL6340SLLSQ"
			(at 0 6.4 180)
			(unlocked yes)
			(layer "F.Fab")
			(effects
				(font
					(size 0.7 0.7)
					(thickness 0.15)
				)
			)
		)
		(property "Datasheet" "https://www.thunderbolttechnology.net/sites/default/files/18-241_ThunderboltController_Brief_HI.pdf"
			(at 0 0 180)
			(layer "F.Fab")
			(hide yes)
			(effects
				(font
					(size 1.27 1.27)
					(thickness 0.15)
				)
			)
		)
		(property "Description" "Thunderbolt™ 3 Controller, I/O"
			(at 0 0 180)
			(layer "F.Fab")
			(hide yes)
			(effects
				(font
					(size 1.27 1.27)
					(thickness 0.15)
				)
			)
		)
		(property "Manufacturer" "Intel"
			(at 0 0 180)
			(unlocked yes)
			(layer "F.Fab")
			(hide yes)
			(effects
				(font
					(size 1 1)
					(thickness 0.15)
				)
			)
		)
		(property "MPN" "JHL6340SLLSQ"
			(at 0 0 180)
			(unlocked yes)
			(layer "F.Fab")
			(hide yes)
			(effects
				(font
					(size 1 1)
					(thickness 0.15)
				)
			)
		)
		(property "Author" "Antmicro"
			(at 0 0 180)
			(unlocked yes)
			(layer "F.Fab")
			(hide yes)
			(effects
				(font
					(size 1 1)
					(thickness 0.15)
				)
			)
		)
		(property "License" "Apache-2.0"
			(at 0 0 180)
			(unlocked yes)
			(layer "F.Fab")
			(hide yes)
			(effects
				(font
					(size 1 1)
					(thickness 0.15)
				)
			)
		)
		(sheetname "/TB Controller/")
		(sheetfile "tb.kicad_sch")
		(attr smd)
		(pad "A1" smd circle
			(at -5.06 -5.06 180)
			(size 0.254 0.254)
			(layers "F.Cu" "F.Mask" "F.Paste")
			(net 23 "GND")
			(pinfunction "SVR_VSS")
			(pintype "power_in")
		)
		(pad "A2" smd oval
			(at -4.6 -5.06 180)
			(size 0.1578 0.3302)
			(layers "F.Cu" "F.Mask" "F.Paste")
			(net 57 "+3V3_TB")
			(pinfunction "VCC3P3_SVR")
			(pintype "power_in")
		)
		(pad "A3" smd oval
			(at -4.14 -5.06 180)
			(size 0.1578 0.3302)
			(layers "F.Cu" "F.Mask" "F.Paste")
			(net 57 "+3V3_TB")
			(pinfunction "VCC3P3_SVR")
			(pintype "passive")
		)
		(pad "A4" smd oval
			(at -3.68 -5.06 180)
			(size 0.1578 0.3302)
			(layers "F.Cu" "F.Mask" "F.Paste")
			(net 376 "/PD and TB DC-DC/LSX_1.LSX_P2R")
			(pinfunction "PA_LSRX")
			(pintype "input")
		)
		(pad "A5" smd oval
			(at -3.22 -5.06 180)
			(size 0.1578 0.3302)
			(layers "F.Cu" "F.Mask" "F.Paste")
			(net 383 "/PD and TB DC-DC/LSX_1.LSX_R2P")
			(pinfunction "PA_LSTX")
			(pintype "output")
		)
		(pad "A6" smd oval
			(at -2.76 -5.06 180)
			(size 0.1578 0.3302)
			(layers "F.Cu" "F.Mask" "F.Paste")
			(net 23 "GND")
			(pinfunction "VSS_ANA")
			(pintype "passive")
		)
		(pad "A7" smd oval
			(at -2.3 -5.06 180)
			(size 0.1578 0.3302)
			(layers "F.Cu" "F.Mask" "F.Paste")
			(net 242 "unconnected-(U4E-PB_RX1_N-PadA7)")
			(pinfunction "PB_RX1_N")
			(pintype "input+no_connect")
		)
		(pad "A8" smd oval
			(at -1.84 -5.06 180)
			(size 0.1578 0.3302)
			(layers "F.Cu" "F.Mask" "F.Paste")
			(net 23 "GND")
			(pinfunction "VSS_ANA")
			(pintype "passive")
		)
		(pad "A9" smd oval
			(at -1.38 -5.06 180)
			(size 0.1578 0.3302)
			(layers "F.Cu" "F.Mask" "F.Paste")
			(net 243 "unconnected-(U4E-PB_TX1_P-PadA9)")
			(pinfunction "PB_TX1_P")
			(pintype "output+no_connect")
		)
		(pad "A10" smd oval
			(at -0.92 -5.06 180)
			(size 0.1578 0.3302)
			(layers "F.Cu" "F.Mask" "F.Paste")
			(net 23 "GND")
			(pinfunction "VSS_ANA")
			(pintype "passive")
		)
		(pad "A11" smd oval
			(at -0.46 -5.06 180)
			(size 0.1578 0.3302)
			(layers "F.Cu" "F.Mask" "F.Paste")
			(net 244 "unconnected-(U4E-PB_TX0_P-PadA11)")
			(pinfunction "PB_TX0_P")
			(pintype "output+no_connect")
		)
		(pad "A12" smd oval
			(at 0 -5.06 180)
			(size 0.1578 0.3302)
			(layers "F.Cu" "F.Mask" "F.Paste")
			(net 23 "GND")
			(pinfunction "VSS_ANA")
			(pintype "passive")
		)
		(pad "A13" smd oval
			(at 0.46 -5.06 180)
			(size 0.1578 0.3302)
			(layers "F.Cu" "F.Mask" "F.Paste")
			(net 245 "unconnected-(U4E-PB_RX0_P-PadA13)")
			(pinfunction "PB_RX0_P")
			(pintype "input+no_connect")
		)
		(pad "A14" smd oval
			(at 0.92 -5.06 180)
			(size 0.1578 0.3302)
			(layers "F.Cu" "F.Mask" "F.Paste")
			(net 23 "GND")
			(pinfunction "VSS_ANA")
			(pintype "passive")
		)
		(pad "A15" smd oval
			(at 1.38 -5.06 180)
			(size 0.1578 0.3302)
			(layers "F.Cu" "F.Mask" "F.Paste")
			(net 362 "/PD and TB DC-DC/USB3.RX1_P")
			(pinfunction "PA_RX1_P")
			(pintype "input")
		)
		(pad "A16" smd oval
			(at 1.84 -5.06 180)
			(size 0.1578 0.3302)
			(layers "F.Cu" "F.Mask" "F.Paste")
			(net 23 "GND")
			(pinfunction "VSS_ANA")
			(pintype "passive")
		)
		(pad "A17" smd oval
			(at 2.3 -5.06 180)
			(size 0.1578 0.3302)
			(layers "F.Cu" "F.Mask" "F.Paste")
			(net 168 "/TB Controller/PA_TX1_P")
			(pinfunction "PA_TX1_P")
			(pintype "output")
		)
		(pad "A18" smd oval
			(at 2.76 -5.06 180)
			(size 0.1578 0.3302)
			(layers "F.Cu" "F.Mask" "F.Paste")
			(net 23 "GND")
			(pinfunction "VSS_ANA")
			(pintype "passive")
		)
		(pad "A19" smd oval
			(at 3.22 -5.06 180)
			(size 0.1578 0.3302)
			(layers "F.Cu" "F.Mask" "F.Paste")
			(net 167 "/TB Controller/PA_TX0_P")
			(pinfunction "PA_TX0_P")
			(pintype "output")
		)
		(pad "A20" smd oval
			(at 3.68 -5.06 180)
			(size 0.1578 0.3302)
			(layers "F.Cu" "F.Mask" "F.Paste")
			(net 23 "GND")
			(pinfunction "VSS_ANA")
			(pintype "passive")
		)
		(pad "A21" smd oval
			(at 4.14 -5.06 180)
			(size 0.1578 0.3302)
			(layers "F.Cu" "F.Mask" "F.Paste")
			(net 363 "/PD and TB DC-DC/USB3.RX0_N")
			(pinfunction "PA_RX0_N")
			(pintype "input")
		)
		(pad "A22" smd oval
			(at 4.6 -5.06 180)
			(size 0.1578 0.3302)
			(layers "F.Cu" "F.Mask" "F.Paste")
			(net 23 "GND")
			(pinfunction "VSS_ANA")
			(pintype "passive")
		)
		(pad "A23" smd circle
			(at 5.06 -5.06 180)
			(size 0.254 0.254)
			(layers "F.Cu" "F.Mask" "F.Paste")
			(net 246 "unconnected-(U4F-ATEST_P-PadA23)")
			(pinfunction "ATEST_P")
			(pintype "passive+no_connect")
		)
		(pad "AA1" smd oval
			(at -5.06 4.14 270)
			(size 0.1578 0.3302)
			(layers "F.Cu" "F.Mask" "F.Paste")
			(net 191 "Net-(U4C-GPIO_8)")
			(pinfunction "GPIO_8")
			(pintype "bidirectional")
		)
		(pad "AA2" smd circle
			(at -4.6 4.14 180)
			(size 0.254 0.254)
			(layers "F.Cu" "F.Mask" "F.Paste")
			(net 217 "Net-(U4C-DPSNK0_HPD)")
			(pinfunction "DPSNK0_HPD")
			(pintype "passive")
		)
		(pad "AA22" smd circle
			(at 4.6 4.14 180)
			(size 0.254 0.254)
			(layers "F.Cu" "F.Mask" "F.Paste")
			(net 23 "GND")
			(pinfunction "VSS_ANA")
			(pintype "passive")
		)
		(pad "AA23" smd oval
			(at 5.06 4.14 270)
			(size 0.1578 0.3302)
			(layers "F.Cu" "F.Mask" "F.Paste")
			(net 23 "GND")
			(pinfunction "VSS_ANA")
			(pintype "passive")
		)
		(pad "AB1" smd oval
			(at -5.06 4.6 270)
			(size 0.1578 0.3302)
			(layers "F.Cu" "F.Mask" "F.Paste")
			(net 23 "GND")
			(pinfunction "VSS")
			(pintype "passive")
		)
		(pad "AB2" smd circle
			(at -4.6 4.6 180)
			(size 0.254 0.254)
			(layers "F.Cu" "F.Mask" "F.Paste")
			(net 23 "GND")
			(pinfunction "MONDC_DPSRC")
			(pintype "passive")
		)
		(pad "AB3" smd circle
			(at -4.14 4.6 180)
			(size 0.254 0.254)
			(layers "F.Cu" "F.Mask" "F.Paste")
			(net 398 "/PD and TB DC-DC/TB_FLASH.MOSI")
			(pinfunction "EE_DI")
			(pintype "output")
		)
		(pad "AB4" smd circle
			(at -3.68 4.6 180)
			(size 0.254 0.254)
			(layers "F.Cu" "F.Mask" "F.Paste")
			(net 397 "/PD and TB DC-DC/TB_FLASH.CLK")
			(pinfunction "EE_CLK")
			(pintype "output")
		)
		(pad "AB5" smd circle
			(at -3.22 4.6 180)
			(size 0.254 0.254)
			(layers "F.Cu" "F.Mask" "F.Paste")
			(net 238 "Net-(U4D-TEST_PWR_GOOD)")
			(pinfunction "TEST_PWR_GOOD")
			(pintype "input")
		)
		(pad "AB6" smd circle
			(at -2.76 4.6 180)
			(size 0.254 0.254)
			(layers "F.Cu" "F.Mask" "F.Paste")
			(net 23 "GND")
			(pinfunction "VSS_ANA")
			(pintype "passive")
		)
		(pad "AB7" smd circle
			(at -2.3 4.6 180)
			(size 0.254 0.254)
			(layers "F.Cu" "F.Mask" "F.Paste")
			(net 247 "unconnected-(U4C-DPSNK0_ML0_P-PadAB7)")
			(pinfunction "DPSNK0_ML0_P")
			(pintype "input+no_connect")
		)
		(pad "AB8" smd circle
			(at -1.84 4.6 180)
			(size 0.254 0.254)
			(layers "F.Cu" "F.Mask" "F.Paste")
			(net 23 "GND")
			(pinfunction "VSS_ANA")
			(pintype "passive")
		)
		(pad "AB9" smd circle
			(at -1.38 4.6 180)
			(size 0.254 0.254)
			(layers "F.Cu" "F.Mask" "F.Paste")
			(net 248 "unconnected-(U4C-DPSNK0_ML1_P-PadAB9)")
			(pinfunction "DPSNK0_ML1_P")
			(pintype "input+no_connect")
		)
		(pad "AB10" smd circle
			(at -0.92 4.6 180)
			(size 0.254 0.254)
			(layers "F.Cu" "F.Mask" "F.Paste")
			(net 23 "GND")
			(pinfunction "VSS_ANA")
			(pintype "passive")
		)
		(pad "AB11" smd circle
			(at -0.46 4.6 180)
			(size 0.254 0.254)
			(layers "F.Cu" "F.Mask" "F.Paste")
			(net 249 "unconnected-(U4C-DPSNK0_ML2_P-PadAB11)")
			(pinfunction "DPSNK0_ML2_P")
			(pintype "input+no_connect")
		)
		(pad "AB12" smd circle
			(at 0 4.6 180)
			(size 0.254 0.254)
			(layers "F.Cu" "F.Mask" "F.Paste")
			(net 23 "GND")
			(pinfunction "VSS_ANA")
			(pintype "passive")
		)
		(pad "AB13" smd circle
			(at 0.46 4.6 180)
			(size 0.254 0.254)
			(layers "F.Cu" "F.Mask" "F.Paste")
			(net 250 "unconnected-(U4C-DPSNK0_ML3_P-PadAB13)")
			(pinfunction "DPSNK0_ML3_P")
			(pintype "input+no_connect")
		)
		(pad "AB14" smd circle
			(at 0.92 4.6 180)
			(size 0.254 0.254)
			(layers "F.Cu" "F.Mask" "F.Paste")
			(net 23 "GND")
			(pinfunction "VSS_ANA")
			(pintype "passive")
		)
		(pad "AB15" smd circle
			(at 1.38 4.6 180)
			(size 0.254 0.254)
			(layers "F.Cu" "F.Mask" "F.Paste")
			(net 251 "unconnected-(U4C-DPSNK1_ML0_P-PadAB15)")
			(pinfunction "DPSNK1_ML0_P")
			(pintype "input+no_connect")
		)
		(pad "AB16" smd circle
			(at 1.84 4.6 180)
			(size 0.254 0.254)
			(layers "F.Cu" "F.Mask" "F.Paste")
			(net 23 "GND")
			(pinfunction "VSS_ANA")
			(pintype "passive")
		)
		(pad "AB17" smd circle
			(at 2.3 4.6 180)
			(size 0.254 0.254)
			(layers "F.Cu" "F.Mask" "F.Paste")
			(net 252 "unconnected-(U4C-DPSNK1_ML1_P-PadAB17)")
			(pinfunction "DPSNK1_ML1_P")
			(pintype "input+no_connect")
		)
		(pad "AB18" smd circle
			(at 2.76 4.6 180)
			(size 0.254 0.254)
			(layers "F.Cu" "F.Mask" "F.Paste")
			(net 23 "GND")
			(pinfunction "VSS_ANA")
			(pintype "passive")
		)
		(pad "AB19" smd circle
			(at 3.22 4.6 180)
			(size 0.254 0.254)
			(layers "F.Cu" "F.Mask" "F.Paste")
			(net 253 "unconnected-(U4C-DPSNK1_ML2_P-PadAB19)")
			(pinfunction "DPSNK1_ML2_P")
			(pintype "input+no_connect")
		)
		(pad "AB20" smd circle
			(at 3.68 4.6 180)
			(size 0.254 0.254)
			(layers "F.Cu" "F.Mask" "F.Paste")
			(net 23 "GND")
			(pinfunction "VSS_ANA")
			(pintype "passive")
		)
		(pad "AB21" smd circle
			(at 4.14 4.6 180)
			(size 0.254 0.254)
			(layers "F.Cu" "F.Mask" "F.Paste")
			(net 254 "unconnected-(U4C-DPSNK1_ML3_P-PadAB21)")
			(pinfunction "DPSNK1_ML3_P")
			(pintype "input+no_connect")
		)
		(pad "AB22" smd circle
			(at 4.6 4.6 180)
			(size 0.254 0.254)
			(layers "F.Cu" "F.Mask" "F.Paste")
			(net 23 "GND")
			(pinfunction "VSS_ANA")
			(pintype "passive")
		)
		(pad "AB23" smd oval
			(at 5.06 4.6 270)
			(size 0.1578 0.3302)
			(layers "F.Cu" "F.Mask" "F.Paste")
			(net 255 "unconnected-(U4F-THERMDA2-PadAB23)")
			(pinfunction "THERMDA2")
			(pintype "passive+no_connect")
		)
		(pad "AC1" smd circle
			(at -5.06 5.06 180)
			(size 0.254 0.254)
			(layers "F.Cu" "F.Mask" "F.Paste")
			(net 23 "GND")
			(pinfunction "TEST_EDM")
			(pintype "passive")
		)
		(pad "AC2" smd oval
			(at -4.6 5.06 180)
			(size 0.1578 0.3302)
			(layers "F.Cu" "F.Mask" "F.Paste")
			(net 23 "GND")
			(pinfunction "VSS")
			(pintype "passive")
		)
		(pad "AC3" smd oval
			(at -4.14 5.06 180)
			(size 0.1578 0.3302)
			(layers "F.Cu" "F.Mask" "F.Paste")
			(net 359 "/PD and TB DC-DC/TB_FLASH.~{CE}")
			(pinfunction "EE_CS_N")
			(pintype "output")
		)
		(pad "AC4" smd oval
			(at -3.68 5.06 180)
			(size 0.1578 0.3302)
			(layers "F.Cu" "F.Mask" "F.Paste")
			(net 357 "/PD and TB DC-DC/TB_FLASH.MISO")
			(pinfunction "EE_D0")
			(pintype "input")
		)
		(pad "AC5" smd oval
			(at -3.22 5.06 180)
			(size 0.1578 0.3302)
			(layers "F.Cu" "F.Mask" "F.Paste")
			(net 216 "Net-(U4B-PCIE_CLKREQ_N)")
			(pinfunction "PCIE_CLKREQ_N")
			(pintype "output")
		)
		(pad "AC6" smd oval
			(at -2.76 5.06 180)
			(size 0.1578 0.3302)
			(layers "F.Cu" "F.Mask" "F.Paste")
			(net 23 "GND")
			(pinfunction "VSS_ANA")
			(pintype "passive")
		)
		(pad "AC7" smd oval
			(at -2.3 5.06 180)
			(size 0.1578 0.3302)
			(layers "F.Cu" "F.Mask" "F.Paste")
			(net 256 "unconnected-(U4C-DPSNK0_ML0_N-PadAC7)")
			(pinfunction "DPSNK0_ML0_N")
			(pintype "input+no_connect")
		)
		(pad "AC8" smd oval
			(at -1.84 5.06 180)
			(size 0.1578 0.3302)
			(layers "F.Cu" "F.Mask" "F.Paste")
			(net 23 "GND")
			(pinfunction "VSS_ANA")
			(pintype "passive")
		)
		(pad "AC9" smd oval
			(at -1.38 5.06 180)
			(size 0.1578 0.3302)
			(layers "F.Cu" "F.Mask" "F.Paste")
			(net 257 "unconnected-(U4C-DPSNK0_ML1_N-PadAC9)")
			(pinfunction "DPSNK0_ML1_N")
			(pintype "input+no_connect")
		)
		(pad "AC10" smd oval
			(at -0.92 5.06 180)
			(size 0.1578 0.3302)
			(layers "F.Cu" "F.Mask" "F.Paste")
			(net 23 "GND")
			(pinfunction "VSS_ANA")
			(pintype "passive")
		)
		(pad "AC11" smd oval
			(at -0.46 5.06 180)
			(size 0.1578 0.3302)
			(layers "F.Cu" "F.Mask" "F.Paste")
			(net 258 "unconnected-(U4C-DPSNK0_ML2_N-PadAC11)")
			(pinfunction "DPSNK0_ML2_N")
			(pintype "input+no_connect")
		)
		(pad "AC12" smd oval
			(at 0 5.06 180)
			(size 0.1578 0.3302)
			(layers "F.Cu" "F.Mask" "F.Paste")
			(net 23 "GND")
			(pinfunction "VSS_ANA")
			(pintype "passive")
		)
		(pad "AC13" smd oval
			(at 0.46 5.06 180)
			(size 0.1578 0.3302)
			(layers "F.Cu" "F.Mask" "F.Paste")
			(net 259 "unconnected-(U4C-DPSNK0_ML3_N-PadAC13)")
			(pinfunction "DPSNK0_ML3_N")
			(pintype "input+no_connect")
		)
		(pad "AC14" smd oval
			(at 0.92 5.06 180)
			(size 0.1578 0.3302)
			(layers "F.Cu" "F.Mask" "F.Paste")
			(net 23 "GND")
			(pinfunction "VSS_ANA")
			(pintype "passive")
		)
		(pad "AC15" smd oval
			(at 1.38 5.06 180)
			(size 0.1578 0.3302)
			(layers "F.Cu" "F.Mask" "F.Paste")
			(net 260 "unconnected-(U4C-DPSNK1_ML0_N-PadAC15)")
			(pinfunction "DPSNK1_ML0_N")
			(pintype "input+no_connect")
		)
		(pad "AC16" smd oval
			(at 1.84 5.06 180)
			(size 0.1578 0.3302)
			(layers "F.Cu" "F.Mask" "F.Paste")
			(net 23 "GND")
			(pinfunction "VSS_ANA")
			(pintype "passive")
		)
		(pad "AC17" smd oval
			(at 2.3 5.06 180)
			(size 0.1578 0.3302)
			(layers "F.Cu" "F.Mask" "F.Paste")
			(net 261 "unconnected-(U4C-DPSNK1_ML1_N-PadAC17)")
			(pinfunction "DPSNK1_ML1_N")
			(pintype "input+no_connect")
		)
		(pad "AC18" smd oval
			(at 2.76 5.06 180)
			(size 0.1578 0.3302)
			(layers "F.Cu" "F.Mask" "F.Paste")
			(net 23 "GND")
			(pinfunction "VSS_ANA")
			(pintype "passive")
		)
		(pad "AC19" smd oval
			(at 3.22 5.06 180)
			(size 0.1578 0.3302)
			(layers "F.Cu" "F.Mask" "F.Paste")
			(net 262 "unconnected-(U4C-DPSNK1_ML2_N-PadAC19)")
			(pinfunction "DPSNK1_ML2_N")
			(pintype "input+no_connect")
		)
		(pad "AC20" smd oval
			(at 3.68 5.06 180)
			(size 0.1578 0.3302)
			(layers "F.Cu" "F.Mask" "F.Paste")
			(net 23 "GND")
			(pinfunction "VSS_ANA")
			(pintype "passive")
		)
		(pad "AC21" smd oval
			(at 4.14 5.06 180)
			(size 0.1578 0.3302)
			(layers "F.Cu" "F.Mask" "F.Paste")
			(net 263 "unconnected-(U4C-DPSNK1_ML3_N-PadAC21)")
			(pinfunction "DPSNK1_ML3_N")
			(pintype "input+no_connect")
		)
		(pad "AC22" smd oval
			(at 4.6 5.06 180)
			(size 0.1578 0.3302)
			(layers "F.Cu" "F.Mask" "F.Paste")
			(net 23 "GND")
			(pinfunction "VSS_ANA")
			(pintype "passive")
		)
		(pad "AC23" smd circle
			(at 5.06 5.06 180)
			(size 0.254 0.254)
			(layers "F.Cu" "F.Mask" "F.Paste")
			(net 264 "unconnected-(U4F-THERMDA1-PadAC23)")
			(pinfunction "THERMDA1")
			(pintype "passive+no_connect")
		)
		(pad "B1" smd oval
			(at -5.06 -4.6 270)
			(size 0.1578 0.3302)
			(layers "F.Cu" "F.Mask" "F.Paste")
			(net 23 "GND")
			(pinfunction "SVR_VSS")
			(pintype "passive")
		)
		(pad "B2" smd circle
			(at -4.6 -4.6 180)
			(size 0.254 0.254)
			(layers "F.Cu" "F.Mask" "F.Paste")
			(net 23 "GND")
			(pinfunction "SVR_VSS")
			(pintype "passive")
		)
		(pad "B3" smd circle
			(at -4.14 -4.6 180)
			(size 0.254 0.254)
			(layers "F.Cu" "F.Mask" "F.Paste")
			(net 57 "+3V3_TB")
			(pinfunction "VCC3P3_SVR")
			(pintype "passive")
		)
		(pad "B4" smd circle
			(at -3.68 -4.6 180)
			(size 0.254 0.254)
			(layers "F.Cu" "F.Mask" "F.Paste")
			(net 231 "Net-(U4E-PB_LSTX)")
			(pinfunction "PB_LSTX")
			(pintype "output")
		)
		(pad "B5" smd circle
			(at -3.22 -4.6 180)
			(size 0.254 0.254)
			(layers "F.Cu" "F.Mask" "F.Paste")
			(net 232 "Net-(U4E-PB_LSRX)")
			(pinfunction "PB_LSRX")
			(pintype "input")
		)
		(pad "B6" smd circle
			(at -2.76 -4.6 180)
			(size 0.254 0.254)
			(layers "F.Cu" "F.Mask" "F.Paste")
			(net 23 "GND")
			(pinfunction "VSS_ANA")
			(pintype "passive")
		)
	)
)
